# S9S_MB_2U (Grand Teton) — schematic netlist excerpt (pin names and nets, part order shuffled) for the footprints in the layout excerpt that follows; sources: Cadence DE-HDL packaged netlist, KiCad conversion of 03242023_DA0F0TMBIJ0_F0T_Motherboard_J_brd_V01_OCP.brd

PU78_P1_4  ISL99390FRZTR5935  ISL99390FRZ-TR5935 IC  pkg QFN21_6X5XB  page 290
  VOS  = PVCCFA_EHV_FIVRA_CPU1_VOS4
  AGND  = GND
  VCC  = PVCCFA_EHV_FIVRA_CPU1_VDD4
  PVCC  = PVCCFA_EHV_FIVRA_CPU1_PVCC2
  PGND1  = GND
  GL1  = NC
  PGND2  = GND
  SW  = SW_PVCCFA_EHV_FIVRA_CPU1_SW4
  VIN1  = SW_P12V_PVCCFA_EHV_FIVRA_CPU1_L
  VIN2  = SW_P12V_PVCCFA_EHV_FIVRA_CPU1_L
  DNC  = NC
  PHASE  = SW_PVCCFA_EHV_FIVRA_CPU1_BOOTR4
  BOOT  = SW_PVCCFA_EHV_FIVRA_CPU1_BOOT4
  PWM  = PVCCFA_EHV_FIVRA_CPU1_PWM4
  EN  = PVCCFA_EHV_FIVRA_CPU1_VDD4
  TOUT_FLT  = PVCCFA_EHV_FIVRA_CPU1_BTSEN
  LSET  = PVCCFA_EHV_FIVRA_CPU1_LSET4
  IOUT  = PVCCFA_EHV_FIVRA_CPU1_IMON4
  REFIN  = PVCCIN_CPU1_VREF
  PGND3  = GND
  GL2  = NC

(kicad_pcb
	(version 20260206)
	(generator "pcbnew")
	(generator_version "10.0")
	(general
		(thickness 1.6)
		(legacy_teardrops no)
	)
	(paper "A4")
	(title_block
		(title "03242023_DA0F0TMBIJ0_F0T_Motherboard_J_brd_V01_OCP.brd")
		(comment 1 "Grand Teton / footprints 1068-1068 of 6105")
	)
	(layers
		(0 "F.Cu" signal "TOP")
		(4 "In1.Cu" signal "GND")
		(6 "In2.Cu" signal "IN1")
		(8 "In3.Cu" signal "GND1")
		(10 "In4.Cu" signal "IN2")
		(12 "In5.Cu" signal "GND2")
		(14 "In6.Cu" signal "IN3")
		(16 "In7.Cu" signal "GND3")
		(18 "In8.Cu" signal "VCC")
		(20 "In9.Cu" signal "VCC1")
		(22 "In10.Cu" signal "GND4")
		(24 "In11.Cu" signal "IN4")
		(26 "In12.Cu" signal "GND5")
		(28 "In13.Cu" signal "IN5")
		(30 "In14.Cu" signal "GND6")
		(32 "In15.Cu" signal "IN6")
		(34 "In16.Cu" signal "GND7")
		(2 "B.Cu" signal "BOTTOM")
		(9 "F.Adhes" user "F.Adhesive")
		(11 "B.Adhes" user "B.Adhesive")
		(13 "F.Paste" user "Package Geometry/Pastemask Top")
		(15 "B.Paste" user "Package Geometry/Pastemask Bottom")
		(5 "F.SilkS" user "Ref Des/Silkscreen Top")
		(7 "B.SilkS" user "Ref Des/Silkscreen Bottom")
		(1 "F.Mask" user "Board Geometry/Soldermask Top")
		(3 "B.Mask" user "Board Geometry/Soldermask Bottom")
		(17 "Dwgs.User" user "User.Drawings")
		(19 "Cmts.User" user "User.Comments")
		(21 "Eco1.User" user "User.Eco1")
		(23 "Eco2.User" user "User.Eco2")
		(25 "Edge.Cuts" user "Board Geometry/Outline")
		(27 "Margin" user)
		(31 "F.CrtYd" user "Package Geometry/Place Bound Top")
		(29 "B.CrtYd" user "Package Geometry/Place Bound Bottom")
		(35 "F.Fab" user "Ref Des/Assembly Top")
		(33 "B.Fab" user "Ref Des/Assembly Bottom")
	)
	(footprint ""
		(layer "F.Cu")
		(at 41.565068 -353.547934)
		(property "Reference" "PU78_P1_4"
			(at -13.965428 -4.667504 0)
			(unlocked yes)
			(layer "F.SilkS")
			(effects
				(font
					(size 0.7874 0.5842)
					(thickness 0.1524)
				)
				(justify left)
			)
		)
		(property "Value" ""
			(at 0 0 0)
			(layer "F.Fab")
			(effects
				(font
					(size 1.27 1.27)
				)
			)
		)
		(duplicate_pad_numbers_are_jumpers no)
		(fp_line
			(start -2.500122 -2.999994)
			(end -2.24409 -2.999994)
			(stroke
				(width 0.1524)
				(type default)
			)
			(layer "F.SilkS")
		)
		(fp_line
			(start -2.500122 -2.529078)
			(end -2.500122 -2.999994)
			(stroke
				(width 0.1524)
				(type default)
			)
			(layer "F.SilkS")
		)
		(fp_line
			(start -2.500122 0.6604)
			(end -2.500122 0.229108)
			(stroke
				(width 0.1524)
				(type default)
			)
			(layer "F.SilkS")
		)
		(fp_line
			(start -2.500122 2.999994)
			(end -2.500122 2.339594)
			(stroke
				(width 0.1524)
				(type default)
			)
			(layer "F.SilkS")
		)
		(fp_line
			(start -2.2987 2.999994)
			(end -2.500122 2.999994)
			(stroke
				(width 0.1524)
				(type default)
			)
			(layer "F.SilkS")
		)
		(fp_line
			(start 2.31394 -2.999994)
			(end 2.500122 -2.999994)
			(stroke
				(width 0.1524)
				(type default)
			)
			(layer "F.SilkS")
		)
		(fp_line
			(start 2.500122 -2.999994)
			(end 2.500122 -2.44348)
			(stroke
				(width 0.1524)
				(type default)
			)
			(layer "F.SilkS")
		)
		(fp_line
			(start 2.500122 2.339594)
			(end 2.500122 2.999994)
			(stroke
				(width 0.1524)
				(type default)
			)
			(layer "F.SilkS")
		)
		(fp_line
			(start 2.500122 2.999994)
			(end 2.2987 2.999994)
			(stroke
				(width 0.1524)
				(type default)
			)
			(layer "F.SilkS")
		)
		(fp_poly
			(pts
				(xy -5.457952 -2.871978) (xy -4.441952 -2.363978) (xy -5.457952 -1.855978)
			)
			(stroke
				(width 0)
				(type default)
			)
			(fill yes)
			(layer "F.SilkS")
		)
		(fp_line
			(start -2.500122 -2.999994)
			(end 2.500122 -2.999994)
			(stroke
				(width 0.1)
				(type default)
			)
			(layer "F.Fab")
		)
		(fp_line
			(start -2.500122 2.999994)
			(end -2.500122 -2.999994)
			(stroke
				(width 0.1)
				(type default)
			)
			(layer "F.Fab")
		)
		(fp_line
			(start 2.500122 -2.999994)
			(end 2.500122 2.999994)
			(stroke
				(width 0.1)
				(type default)
			)
			(layer "F.Fab")
		)
		(fp_line
			(start 2.500122 2.999994)
			(end -2.500122 2.999994)
			(stroke
				(width 0.1)
				(type default)
			)
			(layer "F.Fab")
		)
		(fp_poly
			(pts
				(xy -4.218432 -2.783078) (xy -4.218432 -1.767078) (xy -3.202432 -2.275078)
			)
			(stroke
				(width 0)
				(type default)
			)
			(fill yes)
			(layer "F.Fab")
		)
		(pad "1" smd rect
			(at -2.400046 -2.275078 90)
			(size 0.2286 0.6096)
			(layers "F.Cu" "F.Mask" "F.Paste")
			(net "PVCCFA_EHV_FIVRA_CPU1_VOS4")
		)
		(pad "2" smd rect
			(at -2.400046 -1.82499 90)
			(size 0.2286 0.6096)
			(layers "F.Cu" "F.Mask" "F.Paste")
			(net "GND")
		)
		(pad "3" smd rect
			(at -2.400046 -1.374902 90)
			(size 0.2286 0.6096)
			(layers "F.Cu" "F.Mask" "F.Paste")
			(net "PVCCFA_EHV_FIVRA_CPU1_VDD4")
		)
		(pad "4" smd rect
			(at -2.400046 -0.925068 90)
			(size 0.2286 0.6096)
			(layers "F.Cu" "F.Mask" "F.Paste")
			(net "PVCCFA_EHV_FIVRA_CPU1_PVCC2")
		)
		(pad "5" smd rect
			(at -2.400046 -0.47498 90)
			(size 0.2286 0.6096)
			(layers "F.Cu" "F.Mask" "F.Paste")
			(net "GND")
		)
		(pad "6" smd rect
			(at -2.400046 -0.024892 90)
			(size 0.2286 0.6096)
			(layers "F.Cu" "F.Mask" "F.Paste")
			(net "Net_8496")
		)
		(pad "7_9-20_24" smd circle
			(at 0 1.150112 90)
			(size 0 0)
			(layers "F.Cu" "F.Mask" "F.Paste")
			(net "GND")
		)
		(pad "10_19" smd rect
			(at 0 2.899918 90)
			(size 0.6096 4.318)
			(layers "F.Cu" "F.Mask" "F.Paste")
			(net "SW_PVCCFA_EHV_FIVRA_CPU1_SW4")
		)
		(pad "25_29" smd rect
			(at 1.549908 -1.279906 270)
			(size 2.0574 2.3114)
			(layers "F.Cu" "F.Mask" "F.Paste")
			(net "SW_P12V_PVCCFA_EHV_FIVRA_CPU1_L")
		)
		(pad "30" smd rect
			(at 2.05994 -2.899918)
			(size 0.2286 0.6096)
			(layers "F.Cu" "F.Mask" "F.Paste")
			(net "SW_P12V_PVCCFA_EHV_FIVRA_CPU1_L")
		)
		(pad "31" smd rect
			(at 1.610106 -2.899918)
			(size 0.2286 0.6096)
			(layers "F.Cu" "F.Mask" "F.Paste")
			(net "Net_8497")
		)
		(pad "32" smd rect
			(at 1.160018 -2.899918)
			(size 0.2286 0.6096)
			(layers "F.Cu" "F.Mask" "F.Paste")
			(net "SW_PVCCFA_EHV_FIVRA_CPU1_BOOTR4")
		)
		(pad "33" smd rect
			(at 0.70993 -2.899918)
			(size 0.2286 0.6096)
			(layers "F.Cu" "F.Mask" "F.Paste")
			(net "SW_PVCCFA_EHV_FIVRA_CPU1_BOOT4")
		)
		(pad "34" smd rect
			(at 0.260096 -2.899918)
			(size 0.2286 0.6096)
			(layers "F.Cu" "F.Mask" "F.Paste")
			(net "PVCCFA_EHV_FIVRA_CPU1_PWM4")
		)
		(pad "35" smd rect
			(at -0.189992 -2.899918)
			(size 0.2286 0.6096)
			(layers "F.Cu" "F.Mask" "F.Paste")
			(net "PVCCFA_EHV_FIVRA_CPU1_VDD4")
		)
		(pad "36" smd rect
			(at -0.64008 -2.899918)
			(size 0.2286 0.6096)
			(layers "F.Cu" "F.Mask" "F.Paste")
			(net "PVCCFA_EHV_FIVRA_CPU1_BTSEN")
		)
		(pad "37" smd rect
			(at -1.089914 -2.899918)
			(size 0.2286 0.6096)
			(layers "F.Cu" "F.Mask" "F.Paste")
			(net "PVCCFA_EHV_FIVRA_CPU1_LSET4")
		)
		(pad "38" smd rect
			(at -1.540002 -2.899918)
			(size 0.2286 0.6096)
			(layers "F.Cu" "F.Mask" "F.Paste")
			(net "PVCCFA_EHV_FIVRA_CPU1_IMON4")
		)
		(pad "39" smd rect
			(at -1.99009 -2.899918)
			(size 0.2286 0.6096)
			(layers "F.Cu" "F.Mask" "F.Paste")
			(net "PVCCIN_CPU1_VREF")
		)
		(pad "40" smd rect
			(at -0.87503 -1.27508)
			(size 1.7526 1.9558)
			(layers "F.Cu" "F.Mask" "F.Paste")
			(net "GND")
		)
		(pad "41" smd rect
			(at -1.525016 0.249936 270)
			(size 0.3048 0.4572)
			(layers "F.Cu" "F.Mask" "F.Paste")
			(net "Net_8495")
		)
		(zone
			(layer "F.Cu")
			(hatch none 0.5)
			(connect_pads
				(clearance 0)
			)
			(min_thickness 0.25)
			(keepout
				(tracks not_allowed)
				(vias allowed)
				(pads allowed)
				(copperpour not_allowed)
				(footprints allowed)
			)
			(placement
				(enabled no)
				(sheetname "")
			)
			(fill
				(thermal_gap 0.5)
				(thermal_bridge_width 0.5)
				(island_removal_mode 0)
			)
			(polygon
				(pts
					(xy 39.064946 -350.54794) (xy 39.064946 -351.267268) (xy 44.06519 -351.267268) (xy 44.06519 -350.54794)
					(xy 43.774868 -350.54794) (xy 43.774868 -351.003616) (xy 39.355268 -351.003616) (xy 39.355268 -350.54794)
				)
			)
		)
		(zone
			(layer "F.Cu")
			(hatch none 0.5)
			(connect_pads
				(clearance 0)
			)
			(min_thickness 0.25)
			(keepout
				(tracks not_allowed)
				(vias allowed)
				(pads allowed)
				(copperpour not_allowed)
				(footprints allowed)
			)
			(placement
				(enabled no)
				(sheetname "")
			)
			(fill
				(thermal_gap 0.5)
				(thermal_bridge_width 0.5)
				(island_removal_mode 0)
			)
			(polygon
				(pts
					(xy 39.520622 -353.794568) (xy 39.762938 -353.794568) (xy 39.762938 -353.794314) (xy 40.54602 -353.794314)
					(xy 40.54602 -353.438968) (xy 40.614346 -353.438968) (xy 40.614346 -352.86696) (xy 40.54602 -352.798634)
					(xy 39.064946 -352.798634) (xy 39.064946 -353.255326) (xy 39.760652 -353.255326) (xy 39.760652 -353.094798)
					(xy 40.319452 -353.094798) (xy 40.319452 -353.501198) (xy 39.760652 -353.501198) (xy 39.760652 -353.280726)
					(xy 39.064946 -353.280726) (xy 39.064946 -353.407726) (xy 39.520622 -353.407726)
				)
			)
		)
	)
)
